(kicad_pcb
	(version 20260206)
	(generator "pcbnew")
	(generator_version "10.0")
	(general
		(thickness 1.6)
		(legacy_teardrops no)
	)
	(paper "A4")
	(title_block
		(title "04192023_DAF0TMB3IC0_F0TG_MB_C_brd_V02_OCP.brd")
		(comment 1 "Grand Teton / footprints 1684-1689 of 8354")
	)
	(layers
		(0 "F.Cu" signal "TOP")
		(4 "In1.Cu" signal "GND")
		(6 "In2.Cu" signal "IN1")
		(8 "In3.Cu" signal "GND1")
		(10 "In4.Cu" signal "IN2")
		(12 "In5.Cu" signal "GND2")
		(14 "In6.Cu" signal "IN3")
		(16 "In7.Cu" signal "GND3")
		(18 "In8.Cu" signal "VCC")
		(20 "In9.Cu" signal "VCC1")
		(22 "In10.Cu" signal "GND4")
		(24 "In11.Cu" signal "IN4")
		(26 "In12.Cu" signal "GND5")
		(28 "In13.Cu" signal "IN5")
		(30 "In14.Cu" signal "GND6")
		(32 "In15.Cu" signal "IN6")
		(34 "In16.Cu" signal "GND7")
		(2 "B.Cu" signal "BOTTOM")
		(9 "F.Adhes" user "F.Adhesive")
		(11 "B.Adhes" user "B.Adhesive")
		(13 "F.Paste" user "Package Geometry/Pastemask Top")
		(15 "B.Paste" user "Package Geometry/Pastemask Bottom")
		(5 "F.SilkS" user "Ref Des/Silkscreen Top")
		(7 "B.SilkS" user "Ref Des/Silkscreen Bottom")
		(1 "F.Mask" user "Board Geometry/Soldermask Top")
		(3 "B.Mask" user "Board Geometry/Soldermask Bottom")
		(17 "Dwgs.User" user "User.Drawings")
		(19 "Cmts.User" user "User.Comments")
		(21 "Eco1.User" user "User.Eco1")
		(23 "Eco2.User" user "User.Eco2")
		(25 "Edge.Cuts" user "Board Geometry/Outline")
		(27 "Margin" user)
		(31 "F.CrtYd" user "Package Geometry/Place Bound Top")
		(29 "B.CrtYd" user "Package Geometry/Place Bound Bottom")
		(35 "F.Fab" user "Ref Des/Assembly Top")
		(33 "B.Fab" user "Ref Des/Assembly Bottom")
	)
	(footprint ""
		(layer "F.Cu")
		(at 190.881 -100.294948 90)
		(property "Reference" "R263"
			(at 0 0 90)
			(layer "F.SilkS")
			(hide yes)
			(effects
				(font
					(size 1.27 1.27)
				)
			)
		)
		(property "Value" ""
			(at 0 0 90)
			(layer "F.Fab")
			(effects
				(font
					(size 1.27 1.27)
				)
			)
		)
		(duplicate_pad_numbers_are_jumpers no)
		(fp_line
			(start 0.7874 -0.4064)
			(end 0.7874 0.4064)
			(stroke
				(width 0.1524)
				(type default)
			)
			(layer "F.SilkS")
		)
		(fp_line
			(start -0.7874 -0.4064)
			(end 0.7874 -0.4064)
			(stroke
				(width 0.1524)
				(type default)
			)
			(layer "F.SilkS")
		)
		(fp_line
			(start 0.7874 0.4064)
			(end -0.7874 0.4064)
			(stroke
				(width 0.1524)
				(type default)
			)
			(layer "F.SilkS")
		)
		(fp_line
			(start -0.7874 0.4064)
			(end -0.7874 -0.4064)
			(stroke
				(width 0.1524)
				(type default)
			)
			(layer "F.SilkS")
		)
		(fp_line
			(start -0.12065 -0.305054)
			(end -0.12065 -0.2794)
			(stroke
				(width 0.1)
				(type default)
			)
			(layer "F.Fab")
		)
		(fp_line
			(start -0.67945 -0.305054)
			(end -0.12065 -0.305054)
			(stroke
				(width 0.1)
				(type default)
			)
			(layer "F.Fab")
		)
		(fp_line
			(start 0.67945 -0.3048)
			(end 0.67945 0.3048)
			(stroke
				(width 0.1)
				(type default)
			)
			(layer "F.Fab")
		)
		(fp_line
			(start 0.12065 -0.3048)
			(end 0.67945 -0.3048)
			(stroke
				(width 0.1)
				(type default)
			)
			(layer "F.Fab")
		)
		(fp_line
			(start 0.12065 -0.2794)
			(end 0.12065 -0.3048)
			(stroke
				(width 0.1)
				(type default)
			)
			(layer "F.Fab")
		)
		(fp_line
			(start -0.12065 -0.2794)
			(end 0.12065 -0.2794)
			(stroke
				(width 0.1)
				(type default)
			)
			(layer "F.Fab")
		)
		(fp_line
			(start 0.120396 0.2794)
			(end -0.12065 0.2794)
			(stroke
				(width 0.1)
				(type default)
			)
			(layer "F.Fab")
		)
		(fp_line
			(start -0.12065 0.2794)
			(end -0.12065 0.3048)
			(stroke
				(width 0.1)
				(type default)
			)
			(layer "F.Fab")
		)
		(fp_line
			(start 0.67945 0.3048)
			(end 0.120396 0.3048)
			(stroke
				(width 0.1)
				(type default)
			)
			(layer "F.Fab")
		)
		(fp_line
			(start 0.120396 0.3048)
			(end 0.120396 0.2794)
			(stroke
				(width 0.1)
				(type default)
			)
			(layer "F.Fab")
		)
		(fp_line
			(start -0.12065 0.3048)
			(end -0.67945 0.3048)
			(stroke
				(width 0.1)
				(type default)
			)
			(layer "F.Fab")
		)
		(fp_line
			(start -0.67945 0.3048)
			(end -0.67945 -0.305054)
			(stroke
				(width 0.1)
				(type default)
			)
			(layer "F.Fab")
		)
		(pad "1" smd circle
			(at -0.40005 0 90)
			(size 0 0)
			(layers "F.Cu" "F.Mask" "F.Paste")
			(net "CPU1_CORETYPE1")
		)
		(pad "2" smd circle
			(at 0.40005 0 90)
			(size 0 0)
			(layers "F.Cu" "F.Mask" "F.Paste")
			(net "FM_CPU1_CORETYPE1")
		)
	)
	(footprint ""
		(layer "F.Cu")
		(at 429.87341 -423.60596 90)
		(property "Reference" "R6247"
			(at 0 0 90)
			(layer "F.SilkS")
			(hide yes)
			(effects
				(font
					(size 1.27 1.27)
				)
			)
		)
		(property "Value" ""
			(at 0 0 90)
			(layer "F.Fab")
			(effects
				(font
					(size 1.27 1.27)
				)
			)
		)
		(duplicate_pad_numbers_are_jumpers no)
		(fp_line
			(start 0.7874 -0.4064)
			(end 0.7874 0.4064)
			(stroke
				(width 0.1524)
				(type default)
			)
			(layer "F.SilkS")
		)
		(fp_line
			(start -0.7874 -0.4064)
			(end 0.7874 -0.4064)
			(stroke
				(width 0.1524)
				(type default)
			)
			(layer "F.SilkS")
		)
		(fp_line
			(start 0.7874 0.4064)
			(end -0.7874 0.4064)
			(stroke
				(width 0.1524)
				(type default)
			)
			(layer "F.SilkS")
		)
		(fp_line
			(start -0.7874 0.4064)
			(end -0.7874 -0.4064)
			(stroke
				(width 0.1524)
				(type default)
			)
			(layer "F.SilkS")
		)
		(fp_line
			(start -0.12065 -0.305054)
			(end -0.12065 -0.2794)
			(stroke
				(width 0.1)
				(type default)
			)
			(layer "F.Fab")
		)
		(fp_line
			(start -0.67945 -0.305054)
			(end -0.12065 -0.305054)
			(stroke
				(width 0.1)
				(type default)
			)
			(layer "F.Fab")
		)
		(fp_line
			(start 0.67945 -0.3048)
			(end 0.67945 0.3048)
			(stroke
				(width 0.1)
				(type default)
			)
			(layer "F.Fab")
		)
		(fp_line
			(start 0.12065 -0.3048)
			(end 0.67945 -0.3048)
			(stroke
				(width 0.1)
				(type default)
			)
			(layer "F.Fab")
		)
		(fp_line
			(start 0.12065 -0.2794)
			(end 0.12065 -0.3048)
			(stroke
				(width 0.1)
				(type default)
			)
			(layer "F.Fab")
		)
		(fp_line
			(start -0.12065 -0.2794)
			(end 0.12065 -0.2794)
			(stroke
				(width 0.1)
				(type default)
			)
			(layer "F.Fab")
		)
		(fp_line
			(start 0.120396 0.2794)
			(end -0.12065 0.2794)
			(stroke
				(width 0.1)
				(type default)
			)
			(layer "F.Fab")
		)
		(fp_line
			(start -0.12065 0.2794)
			(end -0.12065 0.3048)
			(stroke
				(width 0.1)
				(type default)
			)
			(layer "F.Fab")
		)
		(fp_line
			(start 0.67945 0.3048)
			(end 0.120396 0.3048)
			(stroke
				(width 0.1)
				(type default)
			)
			(layer "F.Fab")
		)
		(fp_line
			(start 0.120396 0.3048)
			(end 0.120396 0.2794)
			(stroke
				(width 0.1)
				(type default)
			)
			(layer "F.Fab")
		)
		(fp_line
			(start -0.12065 0.3048)
			(end -0.67945 0.3048)
			(stroke
				(width 0.1)
				(type default)
			)
			(layer "F.Fab")
		)
		(fp_line
			(start -0.67945 0.3048)
			(end -0.67945 -0.305054)
			(stroke
				(width 0.1)
				(type default)
			)
			(layer "F.Fab")
		)
		(pad "1" smd circle
			(at -0.40005 0 90)
			(size 0 0)
			(layers "F.Cu" "F.Mask" "F.Paste")
			(net "P3V3_AUX")
		)
		(pad "2" smd circle
			(at 0.40005 0 90)
			(size 0 0)
			(layers "F.Cu" "F.Mask" "F.Paste")
			(net "HSC_TYPE_ADC_ALERT")
		)
	)
	(footprint ""
		(layer "F.Cu")
		(at 448.051682 -53.20411 90)
		(property "Reference" "PC2342"
			(at 0 0 90)
			(layer "F.SilkS")
			(hide yes)
			(effects
				(font
					(size 1.27 1.27)
				)
			)
		)
		(property "Value" ""
			(at 0 0 90)
			(layer "F.Fab")
			(effects
				(font
					(size 1.27 1.27)
				)
			)
		)
		(duplicate_pad_numbers_are_jumpers no)
		(fp_line
			(start 1.524 -0.762)
			(end 1.524 0.762)
			(stroke
				(width 0.1524)
				(type default)
			)
			(layer "F.SilkS")
		)
		(fp_line
			(start -1.524 -0.762)
			(end 1.524 -0.762)
			(stroke
				(width 0.1524)
				(type default)
			)
			(layer "F.SilkS")
		)
		(fp_line
			(start 1.524 0.762)
			(end -1.524 0.762)
			(stroke
				(width 0.1524)
				(type default)
			)
			(layer "F.SilkS")
		)
		(fp_line
			(start -1.524 0.762)
			(end -1.524 -0.762)
			(stroke
				(width 0.1524)
				(type default)
			)
			(layer "F.SilkS")
		)
		(fp_line
			(start 1.1049 -0.724916)
			(end -1.1049 -0.724916)
			(stroke
				(width 0.1)
				(type default)
			)
			(layer "F.Fab")
		)
		(fp_line
			(start -1.1049 -0.724916)
			(end -1.1049 0.724916)
			(stroke
				(width 0.1)
				(type default)
			)
			(layer "F.Fab")
		)
		(fp_line
			(start 1.1049 0.724916)
			(end 1.1049 -0.724916)
			(stroke
				(width 0.1)
				(type default)
			)
			(layer "F.Fab")
		)
		(fp_line
			(start -1.1049 0.724916)
			(end 1.1049 0.724916)
			(stroke
				(width 0.1)
				(type default)
			)
			(layer "F.Fab")
		)
		(pad "1" smd rect
			(at -0.889 0 270)
			(size 1.016 1.27)
			(layers "F.Cu" "F.Mask" "F.Paste")
			(net "SW_P3V3_AUX_FLT")
		)
		(pad "2" smd rect
			(at 0.889 0 270)
			(size 1.016 1.27)
			(layers "F.Cu" "F.Mask" "F.Paste")
			(net "GND")
		)
	)
	(footprint ""
		(layer "F.Cu")
		(at 36.319968 -135.889238 180)
		(property "Reference" "R3327"
			(at 0 0 180)
			(layer "F.SilkS")
			(hide yes)
			(effects
				(font
					(size 1.27 1.27)
				)
			)
		)
		(property "Value" ""
			(at 0 0 180)
			(layer "F.Fab")
			(effects
				(font
					(size 1.27 1.27)
				)
			)
		)
		(duplicate_pad_numbers_are_jumpers no)
		(fp_line
			(start 0.7874 0.4064)
			(end -0.7874 0.4064)
			(stroke
				(width 0.1524)
				(type default)
			)
			(layer "F.SilkS")
		)
		(fp_line
			(start 0.7874 -0.4064)
			(end 0.7874 0.4064)
			(stroke
				(width 0.1524)
				(type default)
			)
			(layer "F.SilkS")
		)
		(fp_line
			(start -0.7874 0.4064)
			(end -0.7874 -0.4064)
			(stroke
				(width 0.1524)
				(type default)
			)
			(layer "F.SilkS")
		)
		(fp_line
			(start -0.7874 -0.4064)
			(end 0.7874 -0.4064)
			(stroke
				(width 0.1524)
				(type default)
			)
			(layer "F.SilkS")
		)
		(fp_line
			(start 0.67945 0.3048)
			(end 0.120396 0.3048)
			(stroke
				(width 0.1)
				(type default)
			)
			(layer "F.Fab")
		)
		(fp_line
			(start 0.67945 -0.3048)
			(end 0.67945 0.3048)
			(stroke
				(width 0.1)
				(type default)
			)
			(layer "F.Fab")
		)
		(fp_line
			(start 0.12065 -0.2794)
			(end 0.12065 -0.3048)
			(stroke
				(width 0.1)
				(type default)
			)
			(layer "F.Fab")
		)
		(fp_line
			(start 0.12065 -0.3048)
			(end 0.67945 -0.3048)
			(stroke
				(width 0.1)
				(type default)
			)
			(layer "F.Fab")
		)
		(fp_line
			(start 0.120396 0.3048)
			(end 0.120396 0.2794)
			(stroke
				(width 0.1)
				(type default)
			)
			(layer "F.Fab")
		)
		(fp_line
			(start 0.120396 0.2794)
			(end -0.12065 0.2794)
			(stroke
				(width 0.1)
				(type default)
			)
			(layer "F.Fab")
		)
		(fp_line
			(start -0.12065 0.3048)
			(end -0.67945 0.3048)
			(stroke
				(width 0.1)
				(type default)
			)
			(layer "F.Fab")
		)
		(fp_line
			(start -0.12065 0.2794)
			(end -0.12065 0.3048)
			(stroke
				(width 0.1)
				(type default)
			)
			(layer "F.Fab")
		)
		(fp_line
			(start -0.12065 -0.2794)
			(end 0.12065 -0.2794)
			(stroke
				(width 0.1)
				(type default)
			)
			(layer "F.Fab")
		)
		(fp_line
			(start -0.12065 -0.305054)
			(end -0.12065 -0.2794)
			(stroke
				(width 0.1)
				(type default)
			)
			(layer "F.Fab")
		)
		(fp_line
			(start -0.67945 0.3048)
			(end -0.67945 -0.305054)
			(stroke
				(width 0.1)
				(type default)
			)
			(layer "F.Fab")
		)
		(fp_line
			(start -0.67945 -0.305054)
			(end -0.12065 -0.305054)
			(stroke
				(width 0.1)
				(type default)
			)
			(layer "F.Fab")
		)
		(pad "1" smd circle
			(at -0.40005 0 180)
			(size 0 0)
			(layers "F.Cu" "F.Mask" "F.Paste")
			(net "CLK_GEN2_GPU_FPGA_OE_N")
		)
		(pad "2" smd circle
			(at 0.40005 0 180)
			(size 0 0)
			(layers "F.Cu" "F.Mask" "F.Paste")
			(net "CLK_GEN2_GPU_FPGA_OE_R2_N")
		)
	)
	(footprint ""
		(layer "F.Cu")
		(at 180.80863 -149.661118 -90)
		(property "Reference" "C43"
			(at 0 0 270)
			(layer "F.SilkS")
			(hide yes)
			(effects
				(font
					(size 1.27 1.27)
				)
			)
		)
		(property "Value" ""
			(at 0 0 270)
			(layer "F.Fab")
			(effects
				(font
					(size 1.27 1.27)
				)
			)
		)
		(duplicate_pad_numbers_are_jumpers no)
		(fp_line
			(start -0.7874 0.4064)
			(end -0.7874 -0.4064)
			(stroke
				(width 0.1524)
				(type default)
			)
			(layer "F.SilkS")
		)
		(fp_line
			(start 0.7874 0.4064)
			(end -0.7874 0.4064)
			(stroke
				(width 0.1524)
				(type default)
			)
			(layer "F.SilkS")
		)
		(fp_line
			(start -0.7874 -0.4064)
			(end 0.7874 -0.4064)
			(stroke
				(width 0.1524)
				(type default)
			)
			(layer "F.SilkS")
		)
		(fp_line
			(start 0.7874 -0.4064)
			(end 0.7874 0.4064)
			(stroke
				(width 0.1524)
				(type default)
			)
			(layer "F.SilkS")
		)
		(fp_line
			(start -0.67945 0.3048)
			(end -0.67945 -0.305054)
			(stroke
				(width 0.1)
				(type default)
			)
			(layer "F.Fab")
		)
		(fp_line
			(start -0.12065 0.3048)
			(end -0.67945 0.3048)
			(stroke
				(width 0.1)
				(type default)
			)
			(layer "F.Fab")
		)
		(fp_line
			(start 0.120396 0.3048)
			(end 0.120396 0.2794)
			(stroke
				(width 0.1)
				(type default)
			)
			(layer "F.Fab")
		)
		(fp_line
			(start 0.67945 0.3048)
			(end 0.120396 0.3048)
			(stroke
				(width 0.1)
				(type default)
			)
			(layer "F.Fab")
		)
		(fp_line
			(start -0.12065 0.2794)
			(end -0.12065 0.3048)
			(stroke
				(width 0.1)
				(type default)
			)
			(layer "F.Fab")
		)
		(fp_line
			(start 0.120396 0.2794)
			(end -0.12065 0.2794)
			(stroke
				(width 0.1)
				(type default)
			)
			(layer "F.Fab")
		)
		(fp_line
			(start -0.12065 -0.2794)
			(end 0.12065 -0.2794)
			(stroke
				(width 0.1)
				(type default)
			)
			(layer "F.Fab")
		)
		(fp_line
			(start 0.12065 -0.2794)
			(end 0.12065 -0.3048)
			(stroke
				(width 0.1)
				(type default)
			)
			(layer "F.Fab")
		)
		(fp_line
			(start 0.12065 -0.3048)
			(end 0.67945 -0.3048)
			(stroke
				(width 0.1)
				(type default)
			)
			(layer "F.Fab")
		)
		(fp_line
			(start 0.67945 -0.3048)
			(end 0.67945 0.3048)
			(stroke
				(width 0.1)
				(type default)
			)
			(layer "F.Fab")
		)
		(fp_line
			(start -0.67945 -0.305054)
			(end -0.12065 -0.305054)
			(stroke
				(width 0.1)
				(type default)
			)
			(layer "F.Fab")
		)
		(fp_line
			(start -0.12065 -0.305054)
			(end -0.12065 -0.2794)
			(stroke
				(width 0.1)
				(type default)
			)
			(layer "F.Fab")
		)
		(pad "1" smd circle
			(at -0.40005 0 270)
			(size 0 0)
			(layers "F.Cu" "F.Mask" "F.Paste")
			(net "P3V3_AUX")
		)
		(pad "2" smd circle
			(at 0.40005 0 270)
			(size 0 0)
			(layers "F.Cu" "F.Mask" "F.Paste")
			(net "GND")
		)
	)
	(footprint ""
		(layer "F.Cu")
		(at 88.431878 -145.50136 -90)
		(property "Reference" "C5019"
			(at 0 0 270)
			(layer "F.SilkS")
			(hide yes)
			(effects
				(font
					(size 1.27 1.27)
				)
			)
		)
		(property "Value" ""
			(at 0 0 270)
			(layer "F.Fab")
			(effects
				(font
					(size 1.27 1.27)
				)
			)
		)
		(duplicate_pad_numbers_are_jumpers no)
		(fp_line
			(start -0.7874 0.4064)
			(end -0.7874 -0.4064)
			(stroke
				(width 0.1524)
				(type default)
			)
			(layer "F.SilkS")
		)
		(fp_line
			(start 0.7874 0.4064)
			(end -0.7874 0.4064)
			(stroke
				(width 0.1524)
				(type default)
			)
			(layer "F.SilkS")
		)
		(fp_line
			(start -0.7874 -0.4064)
			(end 0.7874 -0.4064)
			(stroke
				(width 0.1524)
				(type default)
			)
			(layer "F.SilkS")
		)
		(fp_line
			(start 0.7874 -0.4064)
			(end 0.7874 0.4064)
			(stroke
				(width 0.1524)
				(type default)
			)
			(layer "F.SilkS")
		)
		(fp_line
			(start -0.67945 0.3048)
			(end -0.67945 -0.305054)
			(stroke
				(width 0.1)
				(type default)
			)
			(layer "F.Fab")
		)
		(fp_line
			(start -0.12065 0.3048)
			(end -0.67945 0.3048)
			(stroke
				(width 0.1)
				(type default)
			)
			(layer "F.Fab")
		)
		(fp_line
			(start 0.120396 0.3048)
			(end 0.120396 0.2794)
			(stroke
				(width 0.1)
				(type default)
			)
			(layer "F.Fab")
		)
		(fp_line
			(start 0.67945 0.3048)
			(end 0.120396 0.3048)
			(stroke
				(width 0.1)
				(type default)
			)
			(layer "F.Fab")
		)
		(fp_line
			(start -0.12065 0.2794)
			(end -0.12065 0.3048)
			(stroke
				(width 0.1)
				(type default)
			)
			(layer "F.Fab")
		)
		(fp_line
			(start 0.120396 0.2794)
			(end -0.12065 0.2794)
			(stroke
				(width 0.1)
				(type default)
			)
			(layer "F.Fab")
		)
		(fp_line
			(start -0.12065 -0.2794)
			(end 0.12065 -0.2794)
			(stroke
				(width 0.1)
				(type default)
			)
			(layer "F.Fab")
		)
		(fp_line
			(start 0.12065 -0.2794)
			(end 0.12065 -0.3048)
			(stroke
				(width 0.1)
				(type default)
			)
			(layer "F.Fab")
		)
		(fp_line
			(start 0.12065 -0.3048)
			(end 0.67945 -0.3048)
			(stroke
				(width 0.1)
				(type default)
			)
			(layer "F.Fab")
		)
		(fp_line
			(start 0.67945 -0.3048)
			(end 0.67945 0.3048)
			(stroke
				(width 0.1)
				(type default)
			)
			(layer "F.Fab")
		)
		(fp_line
			(start -0.67945 -0.305054)
			(end -0.12065 -0.305054)
			(stroke
				(width 0.1)
				(type default)
			)
			(layer "F.Fab")
		)
		(fp_line
			(start -0.12065 -0.305054)
			(end -0.12065 -0.2794)
			(stroke
				(width 0.1)
				(type default)
			)
			(layer "F.Fab")
		)
		(pad "1" smd circle
			(at -0.40005 0 270)
			(size 0 0)
			(layers "F.Cu" "F.Mask" "F.Paste")
			(net "GND")
		)
		(pad "2" smd circle
			(at 0.40005 0 270)
			(size 0 0)
			(layers "F.Cu" "F.Mask" "F.Paste")
			(net "PWRGD_PVDDCR_SOC_P1")
		)
	)
)
